(kicad_pcb
	(version 20260206)
	(generator "pcbnew")
	(generator_version "10.0")
	(general
		(thickness 1.6)
		(legacy_teardrops no)
	)
	(paper "A4")
	(title_block
		(title "Wiwynn_Tioga_Pass_MB.brd")
		(comment 1 "Tioga Pass / footprints 1123-1127 of 4770")
	)
	(layers
		(0 "F.Cu" signal "TOP")
		(4 "In1.Cu" signal "L2GND")
		(6 "In2.Cu" signal "L3")
		(8 "In3.Cu" signal "L4GND")
		(10 "In4.Cu" signal "L5")
		(12 "In5.Cu" signal "L6GND")
		(14 "In6.Cu" signal "L7VCC")
		(16 "In7.Cu" signal "L8VCC")
		(18 "In8.Cu" signal "L9GND")
		(20 "In9.Cu" signal "L10")
		(22 "In10.Cu" signal "L11GND")
		(24 "In11.Cu" signal "L12")
		(26 "In12.Cu" signal "L13GND")
		(2 "B.Cu" signal "BOTTOM")
		(9 "F.Adhes" user "F.Adhesive")
		(11 "B.Adhes" user "B.Adhesive")
		(13 "F.Paste" user "Package Geometry/Pastemask Top")
		(15 "B.Paste" user "Package Geometry/Pastemask Bottom")
		(5 "F.SilkS" user "Ref Des/Silkscreen Top")
		(7 "B.SilkS" user "Ref Des/Silkscreen Bottom")
		(1 "F.Mask" user "Board Geometry/Soldermask Top")
		(3 "B.Mask" user "Board Geometry/Soldermask Bottom")
		(17 "Dwgs.User" user "User.Drawings")
		(19 "Cmts.User" user "User.Comments")
		(21 "Eco1.User" user "User.Eco1")
		(23 "Eco2.User" user "User.Eco2")
		(25 "Edge.Cuts" user "Board Geometry/Outline")
		(27 "Margin" user)
		(31 "F.CrtYd" user "Package Geometry/Place Bound Top")
		(29 "B.CrtYd" user "Package Geometry/Place Bound Bottom")
		(35 "F.Fab" user "Ref Des/Assembly Top")
		(33 "B.Fab" user "Ref Des/Assembly Bottom")
	)
	(footprint ""
		(layer "F.Cu")
		(at 375.5136 -158.2166 -90)
		(property "Reference" "CT64"
			(at 4.90347 8.7884 0)
			(unlocked yes)
			(layer "F.SilkS")
			(effects
				(font
					(size 0.7874 0.5842)
					(thickness 0.1524)
				)
				(justify left)
			)
		)
		(property "Value" ""
			(at 0 0 270)
			(layer "F.Fab")
			(effects
				(font
					(size 1.27 1.27)
				)
			)
		)
		(duplicate_pad_numbers_are_jumpers no)
		(fp_poly
			(pts
				(xy 0.3048 -0.1016) (xy 0.3048 0.9906) (xy -0.3048 0.9906) (xy -0.3048 -0.1016)
			)
			(stroke
				(width 0)
				(type default)
			)
			(fill no)
			(layer "F.CrtYd")
		)
		(fp_line
			(start -0.3048 0.9906)
			(end 0.3048 0.9906)
			(stroke
				(width 0.1)
				(type default)
			)
			(layer "F.Fab")
		)
		(fp_line
			(start 0.3048 0.9906)
			(end 0.3048 -0.1016)
			(stroke
				(width 0.1)
				(type default)
			)
			(layer "F.Fab")
		)
		(fp_line
			(start -0.3048 -0.1016)
			(end -0.3048 0.9906)
			(stroke
				(width 0.1)
				(type default)
			)
			(layer "F.Fab")
		)
		(fp_line
			(start 0.3048 -0.1016)
			(end -0.3048 -0.1016)
			(stroke
				(width 0.1)
				(type default)
			)
			(layer "F.Fab")
		)
		(pad "1" smd rect
			(at 0 0 270)
			(size 0.508 0.508)
			(layers "F.Cu" "F.Mask" "F.Paste")
			(net "A_TSENSE_PVNN_PCH_TMON")
		)
		(pad "2" smd rect
			(at 0 0.889 270)
			(size 0.508 0.508)
			(layers "F.Cu" "F.Mask" "F.Paste")
			(net "GND")
		)
		(zone
			(layer "F.Cu")
			(hatch none 0.5)
			(connect_pads
				(clearance 0)
			)
			(min_thickness 0.25)
			(keepout
				(tracks not_allowed)
				(vias allowed)
				(pads allowed)
				(copperpour not_allowed)
				(footprints allowed)
			)
			(placement
				(enabled no)
				(sheetname "")
			)
			(fill
				(thermal_gap 0.5)
				(thermal_bridge_width 0.5)
				(island_removal_mode 0)
			)
			(polygon
				(pts
					(xy 374.8786 -158.4706) (xy 374.8786 -157.9626) (xy 375.2596 -157.9626) (xy 375.2596 -158.4706)
				)
			)
		)
		(zone
			(layer "F.Cu")
			(hatch none 0.5)
			(connect_pads
				(clearance 0)
			)
			(min_thickness 0.25)
			(keepout
				(tracks allowed)
				(vias not_allowed)
				(pads allowed)
				(copperpour not_allowed)
				(footprints allowed)
			)
			(placement
				(enabled no)
				(sheetname "")
			)
			(fill
				(thermal_gap 0.5)
				(thermal_bridge_width 0.5)
				(island_removal_mode 0)
			)
			(polygon
				(pts
					(xy 375.2596 -158.4706) (xy 375.2596 -157.9626) (xy 374.8786 -157.9626) (xy 374.8786 -158.4706)
				)
			)
		)
	)
	(footprint ""
		(layer "F.Cu")
		(at 389.636 -71.0565 180)
		(property "Reference" "R7E13"
			(at 0 0 180)
			(layer "F.SilkS")
			(hide yes)
			(effects
				(font
					(size 1.27 1.27)
				)
			)
		)
		(property "Value" ""
			(at 0 0 180)
			(layer "F.Fab")
			(effects
				(font
					(size 1.27 1.27)
				)
			)
		)
		(duplicate_pad_numbers_are_jumpers no)
		(fp_poly
			(pts
				(xy -0.2794 -0.1016) (xy 0.2794 -0.1016) (xy 0.2794 0.9906) (xy -0.2794 0.9906)
			)
			(stroke
				(width 0)
				(type default)
			)
			(fill no)
			(layer "F.CrtYd")
		)
		(fp_line
			(start 0.2794 0.9906)
			(end 0.2794 -0.1016)
			(stroke
				(width 0.1)
				(type default)
			)
			(layer "F.Fab")
		)
		(fp_line
			(start 0.2794 -0.1016)
			(end -0.2794 -0.1016)
			(stroke
				(width 0.1)
				(type default)
			)
			(layer "F.Fab")
		)
		(fp_line
			(start -0.2794 0.9906)
			(end 0.2794 0.9906)
			(stroke
				(width 0.1)
				(type default)
			)
			(layer "F.Fab")
		)
		(fp_line
			(start -0.2794 -0.1016)
			(end -0.2794 0.9906)
			(stroke
				(width 0.1)
				(type default)
			)
			(layer "F.Fab")
		)
		(pad "1" smd rect
			(at 0 0 180)
			(size 0.508 0.508)
			(layers "F.Cu" "F.Mask" "F.Paste")
			(net "GND")
		)
		(pad "2" smd rect
			(at 0 0.889 180)
			(size 0.508 0.508)
			(layers "F.Cu" "F.Mask" "F.Paste")
			(net "AGND_P5V_STBY")
		)
		(zone
			(layer "F.Cu")
			(hatch none 0.5)
			(connect_pads
				(clearance 0)
			)
			(min_thickness 0.25)
			(keepout
				(tracks not_allowed)
				(vias allowed)
				(pads allowed)
				(copperpour not_allowed)
				(footprints allowed)
			)
			(placement
				(enabled no)
				(sheetname "")
			)
			(fill
				(thermal_gap 0.5)
				(thermal_bridge_width 0.5)
				(island_removal_mode 0)
			)
			(polygon
				(pts
					(xy 389.89 -71.6915) (xy 389.382 -71.6915) (xy 389.382 -71.3105) (xy 389.89 -71.3105)
				)
			)
		)
		(zone
			(layer "F.Cu")
			(hatch none 0.5)
			(connect_pads
				(clearance 0)
			)
			(min_thickness 0.25)
			(keepout
				(tracks allowed)
				(vias not_allowed)
				(pads allowed)
				(copperpour not_allowed)
				(footprints allowed)
			)
			(placement
				(enabled no)
				(sheetname "")
			)
			(fill
				(thermal_gap 0.5)
				(thermal_bridge_width 0.5)
				(island_removal_mode 0)
			)
			(polygon
				(pts
					(xy 389.89 -71.3105) (xy 389.382 -71.3105) (xy 389.382 -71.6915) (xy 389.89 -71.6915)
				)
			)
		)
	)
	(footprint ""
		(layer "F.Cu")
		(at 164.973 -67.31 -90)
		(property "Reference" "R4D56"
			(at 0 0 270)
			(layer "F.SilkS")
			(hide yes)
			(effects
				(font
					(size 1.27 1.27)
				)
			)
		)
		(property "Value" ""
			(at 0 0 270)
			(layer "F.Fab")
			(effects
				(font
					(size 1.27 1.27)
				)
			)
		)
		(duplicate_pad_numbers_are_jumpers no)
		(fp_poly
			(pts
				(xy -0.2794 -0.1016) (xy 0.2794 -0.1016) (xy 0.2794 0.9906) (xy -0.2794 0.9906)
			)
			(stroke
				(width 0)
				(type default)
			)
			(fill no)
			(layer "F.CrtYd")
		)
		(fp_line
			(start -0.2794 0.9906)
			(end 0.2794 0.9906)
			(stroke
				(width 0.1)
				(type default)
			)
			(layer "F.Fab")
		)
		(fp_line
			(start 0.2794 0.9906)
			(end 0.2794 -0.1016)
			(stroke
				(width 0.1)
				(type default)
			)
			(layer "F.Fab")
		)
		(fp_line
			(start -0.2794 -0.1016)
			(end -0.2794 0.9906)
			(stroke
				(width 0.1)
				(type default)
			)
			(layer "F.Fab")
		)
		(fp_line
			(start 0.2794 -0.1016)
			(end -0.2794 -0.1016)
			(stroke
				(width 0.1)
				(type default)
			)
			(layer "F.Fab")
		)
		(pad "1" smd rect
			(at 0 0 270)
			(size 0.508 0.508)
			(layers "F.Cu" "F.Mask" "F.Paste")
			(net "SVID_ALERT_PVCCIO_CPU1")
		)
		(pad "2" smd rect
			(at 0 0.889 270)
			(size 0.508 0.508)
			(layers "F.Cu" "F.Mask" "F.Paste")
			(net "SVID_ALERT0_CPU1_R_N")
		)
		(zone
			(layer "F.Cu")
			(hatch none 0.5)
			(connect_pads
				(clearance 0)
			)
			(min_thickness 0.25)
			(keepout
				(tracks not_allowed)
				(vias allowed)
				(pads allowed)
				(copperpour not_allowed)
				(footprints allowed)
			)
			(placement
				(enabled no)
				(sheetname "")
			)
			(fill
				(thermal_gap 0.5)
				(thermal_bridge_width 0.5)
				(island_removal_mode 0)
			)
			(polygon
				(pts
					(xy 164.338 -67.564) (xy 164.338 -67.056) (xy 164.719 -67.056) (xy 164.719 -67.564)
				)
			)
		)
		(zone
			(layer "F.Cu")
			(hatch none 0.5)
			(connect_pads
				(clearance 0)
			)
			(min_thickness 0.25)
			(keepout
				(tracks allowed)
				(vias not_allowed)
				(pads allowed)
				(copperpour not_allowed)
				(footprints allowed)
			)
			(placement
				(enabled no)
				(sheetname "")
			)
			(fill
				(thermal_gap 0.5)
				(thermal_bridge_width 0.5)
				(island_removal_mode 0)
			)
			(polygon
				(pts
					(xy 164.719 -67.564) (xy 164.719 -67.056) (xy 164.338 -67.056) (xy 164.338 -67.564)
				)
			)
		)
	)
	(footprint ""
		(layer "F.Cu")
		(at 398.093946 -47.22368 180)
		(property "Reference" "U7F1"
			(at 8.94334 -3.18643 0)
			(unlocked yes)
			(layer "F.SilkS")
			(effects
				(font
					(size 0.7874 0.5842)
					(thickness 0.1524)
				)
				(justify left)
			)
		)
		(property "Value" ""
			(at 0 0 180)
			(layer "F.Fab")
			(effects
				(font
					(size 1.27 1.27)
				)
			)
		)
		(duplicate_pad_numbers_are_jumpers no)
		(fp_line
			(start 11.645392 10.819892)
			(end -2.094738 10.819892)
			(stroke
				(width 0.1524)
				(type default)
			)
			(layer "F.SilkS")
		)
		(fp_line
			(start 11.645392 -1.929892)
			(end 11.645392 10.819892)
			(stroke
				(width 0.1524)
				(type default)
			)
			(layer "F.SilkS")
		)
		(fp_line
			(start -2.094738 10.819892)
			(end -2.094738 -1.929892)
			(stroke
				(width 0.1524)
				(type default)
			)
			(layer "F.SilkS")
		)
		(fp_line
			(start -2.094738 -1.929892)
			(end 11.645392 -1.929892)
			(stroke
				(width 0.1524)
				(type default)
			)
			(layer "F.SilkS")
		)
		(fp_circle
			(center -1.604264 -2.699512)
			(end -1.731264 -2.699512)
			(stroke
				(width 0.762)
				(type default)
			)
			(fill no)
			(layer "F.SilkS")
		)
		(fp_rect
			(start 11.645392 12.260326)
			(end 15.404846 -3.284474)
			(stroke
				(width 0)
				(type default)
			)
			(fill no)
			(layer "F.CrtYd")
		)
		(fp_rect
			(start -5.600954 12.260326)
			(end -2.094738 -3.284474)
			(stroke
				(width 0)
				(type default)
			)
			(fill no)
			(layer "F.CrtYd")
		)
		(fp_poly
			(pts
				(xy 7.569962 10.819892) (xy 6.970014 12.21994) (xy 2.629916 12.21994) (xy 2.029968 10.819892)
			)
			(stroke
				(width 0)
				(type default)
			)
			(fill no)
			(layer "F.CrtYd")
		)
		(fp_poly
			(pts
				(xy 2.029968 -1.929892) (xy 2.629916 -3.32994) (xy 6.970014 -3.32994) (xy 7.569962 -1.929892)
			)
			(stroke
				(width 0)
				(type default)
			)
			(fill no)
			(layer "F.CrtYd")
		)
		(fp_poly
			(pts
				(xy -2.094738 10.819892) (xy 11.645392 10.819892) (xy 11.645392 -1.929892) (xy -2.094738 -1.929892)
			)
			(stroke
				(width 0)
				(type default)
			)
			(fill no)
			(layer "F.CrtYd")
		)
		(fp_line
			(start 11.645392 10.819892)
			(end -2.094738 10.819892)
			(stroke
				(width 0.1)
				(type default)
			)
			(layer "F.Fab")
		)
		(fp_line
			(start 11.645392 -1.929892)
			(end 11.645392 10.819892)
			(stroke
				(width 0.1)
				(type default)
			)
			(layer "F.Fab")
		)
		(fp_line
			(start 7.569962 10.819892)
			(end 6.970014 12.21994)
			(stroke
				(width 0.1)
				(type default)
			)
			(layer "F.Fab")
		)
		(fp_line
			(start 6.970014 12.21994)
			(end 2.629916 12.21994)
			(stroke
				(width 0.1)
				(type default)
			)
			(layer "F.Fab")
		)
		(fp_line
			(start 6.970014 -3.32994)
			(end 7.569962 -1.929892)
			(stroke
				(width 0.1)
				(type default)
			)
			(layer "F.Fab")
		)
		(fp_line
			(start 2.629916 12.21994)
			(end 2.029968 10.819892)
			(stroke
				(width 0.1)
				(type default)
			)
			(layer "F.Fab")
		)
		(fp_line
			(start 2.629916 -3.32994)
			(end 6.970014 -3.32994)
			(stroke
				(width 0.1)
				(type default)
			)
			(layer "F.Fab")
		)
		(fp_line
			(start 2.029968 -1.929892)
			(end 2.629916 -3.32994)
			(stroke
				(width 0.1)
				(type default)
			)
			(layer "F.Fab")
		)
		(fp_line
			(start -2.094738 10.819892)
			(end -2.094738 -1.929892)
			(stroke
				(width 0.1)
				(type default)
			)
			(layer "F.Fab")
		)
		(fp_line
			(start -2.094738 -1.929892)
			(end 11.645392 -1.929892)
			(stroke
				(width 0.1)
				(type default)
			)
			(layer "F.Fab")
		)
		(fp_circle
			(center -2.645918 -0.940054)
			(end -2.772918 -0.940054)
			(stroke
				(width 0.254)
				(type default)
			)
			(fill no)
			(layer "F.Fab")
		)
		(fp_text user "9"
			(at 12.861798 10.70102 270)
			(unlocked yes)
			(layer "F.SilkS")
			(effects
				(font
					(size 0.7874 0.5842)
					(thickness 0.1524)
				)
				(justify left)
			)
		)
		(fp_text user "16"
			(at 11.13917 -2.15392 270)
			(unlocked yes)
			(layer "F.SilkS")
			(effects
				(font
					(size 0.7874 0.5842)
					(thickness 0.1524)
				)
				(justify left)
			)
		)
		(fp_text user "8"
			(at -1.215136 11.422634 0)
			(unlocked yes)
			(layer "F.SilkS")
			(effects
				(font
					(size 0.7874 0.5842)
					(thickness 0.1524)
				)
				(justify left)
			)
		)
		(fp_text user "9"
			(at 11.862054 9.20369 180)
			(unlocked yes)
			(layer "F.Fab")
			(effects
				(font
					(size 0.254 0.254)
					(thickness 0.000001)
				)
				(justify left)
			)
		)
		(fp_text user "16"
			(at 11.646916 0.367792 180)
			(unlocked yes)
			(layer "F.Fab")
			(effects
				(font
					(size 0.254 0.254)
					(thickness 0.000001)
				)
				(justify left)
			)
		)
		(fp_text user "8"
			(at -2.3241 8.86333 180)
			(unlocked yes)
			(layer "F.Fab")
			(effects
				(font
					(size 0.635 0.635)
					(thickness 0.1524)
				)
				(justify left)
			)
		)
		(pad "1" smd rect
			(at 0 0 180)
			(size 1.9304 0.635)
			(layers "F.Cu" "F.Mask" "F.Paste")
			(net "PU_BIOS_SPI_HOLD0_N")
		)
		(pad "2" smd rect
			(at 0 1.27 180)
			(size 1.9304 0.635)
			(layers "F.Cu" "F.Mask" "F.Paste")
			(net "P3V3_STBY")
		)
		(pad "3" smd rect
			(at 0 2.54 180)
			(size 1.9304 0.635)
			(layers "F.Cu" "F.Mask" "F.Paste")
			(net "PU_SPI0_RST")
		)
		(pad "4" smd rect
			(at 0 3.81 180)
			(size 1.9304 0.635)
			(layers "F.Cu" "F.Mask" "F.Paste")
			(net "TP_SPI_0_6")
		)
		(pad "5" smd rect
			(at 0 5.08 180)
			(size 1.9304 0.635)
			(layers "F.Cu" "F.Mask" "F.Paste")
			(net "TP_SPI_0_5")
		)
		(pad "6" smd rect
			(at 0 6.35 180)
			(size 1.9304 0.635)
			(layers "F.Cu" "F.Mask" "F.Paste")
			(net "TP_SPI_0_4")
		)
		(pad "7" smd rect
			(at 0 7.62 180)
			(size 1.9304 0.635)
			(layers "F.Cu" "F.Mask" "F.Paste")
			(net "SPI_CS0_PRIMARY_R_N")
		)
		(pad "8" smd rect
			(at 0 8.89 180)
			(size 1.9304 0.635)
			(layers "F.Cu" "F.Mask" "F.Paste")
			(net "SPI_MISO_R0")
		)
		(pad "9" smd rect
			(at 9.5504 8.89 180)
			(size 1.9304 0.635)
			(layers "F.Cu" "F.Mask" "F.Paste")
			(net "PU_BIOS_SPI_WP0_N")
		)
		(pad "10" smd rect
			(at 9.5504 7.62 180)
			(size 1.9304 0.635)
			(layers "F.Cu" "F.Mask" "F.Paste")
			(net "GND")
		)
		(pad "11" smd rect
			(at 9.5504 6.35 180)
			(size 1.9304 0.635)
			(layers "F.Cu" "F.Mask" "F.Paste")
			(net "TP_SPI_0_3")
		)
		(pad "12" smd rect
			(at 9.5504 5.08 180)
			(size 1.9304 0.635)
			(layers "F.Cu" "F.Mask" "F.Paste")
			(net "TP_SPI_0_2")
		)
		(pad "13" smd rect
			(at 9.5504 3.81 180)
			(size 1.9304 0.635)
			(layers "F.Cu" "F.Mask" "F.Paste")
			(net "TP_SPI_0_1")
		)
		(pad "14" smd rect
			(at 9.5504 2.54 180)
			(size 1.9304 0.635)
			(layers "F.Cu" "F.Mask" "F.Paste")
			(net "TP_SPI_0_0")
		)
		(pad "15" smd rect
			(at 9.5504 1.27 180)
			(size 1.9304 0.635)
			(layers "F.Cu" "F.Mask" "F.Paste")
			(net "SPI_SWITCH_MOSI_R0")
		)
		(pad "16" smd rect
			(at 9.5504 0 180)
			(size 1.9304 0.635)
			(layers "F.Cu" "F.Mask" "F.Paste")
			(net "SPI_CLK_R0")
		)
	)
	(footprint ""
		(layer "F.Cu")
		(at 253.392432 -3.3528 90)
		(property "Reference" "C5G14"
			(at 1.848866 0.752348 90)
			(unlocked yes)
			(layer "F.SilkS")
			(effects
				(font
					(size 1.27 0.9652)
					(thickness 0.1524)
				)
			)
		)
		(property "Value" ""
			(at 0 0 90)
			(layer "F.Fab")
			(effects
				(font
					(size 1.27 1.27)
				)
			)
		)
		(duplicate_pad_numbers_are_jumpers no)
		(fp_rect
			(start -0.500126 1.598422)
			(end 0.500126 -0.201422)
			(stroke
				(width 0)
				(type default)
			)
			(fill no)
			(layer "F.CrtYd")
		)
		(fp_line
			(start 0.500126 -0.201422)
			(end 0.500126 1.598422)
			(stroke
				(width 0.1)
				(type default)
			)
			(layer "F.Fab")
		)
		(fp_line
			(start -0.500126 -0.201422)
			(end 0.500126 -0.201422)
			(stroke
				(width 0.1)
				(type default)
			)
			(layer "F.Fab")
		)
		(fp_line
			(start 0.500126 1.598422)
			(end -0.500126 1.598422)
			(stroke
				(width 0.1)
				(type default)
			)
			(layer "F.Fab")
		)
		(fp_line
			(start -0.500126 1.598422)
			(end -0.500126 -0.201422)
			(stroke
				(width 0.1)
				(type default)
			)
			(layer "F.Fab")
		)
		(pad "1" smd rect
			(at 0 0)
			(size 0.889 0.9906)
			(layers "F.Cu" "F.Mask" "F.Paste")
			(net "PVDDQ_ABC")
		)
		(pad "2" smd rect
			(at 0 1.397)
			(size 0.889 0.9906)
			(layers "F.Cu" "F.Mask" "F.Paste")
			(net "GND")
		)
		(zone
			(layer "F.Cu")
			(hatch none 0.5)
			(connect_pads
				(clearance 0)
			)
			(min_thickness 0.25)
			(keepout
				(tracks not_allowed)
				(vias allowed)
				(pads allowed)
				(copperpour not_allowed)
				(footprints allowed)
			)
			(placement
				(enabled no)
				(sheetname "")
			)
			(fill
				(thermal_gap 0.5)
				(thermal_bridge_width 0.5)
				(island_removal_mode 0)
			)
			(polygon
				(pts
					(xy 254.344932 -2.8575) (xy 254.344932 -3.8481) (xy 253.836932 -3.8481) (xy 253.836932 -2.8575)
				)
			)
		)
		(zone
			(layer "F.Cu")
			(hatch none 0.5)
			(connect_pads
				(clearance 0)
			)
			(min_thickness 0.25)
			(keepout
				(tracks allowed)
				(vias not_allowed)
				(pads allowed)
				(copperpour not_allowed)
				(footprints allowed)
			)
			(placement
				(enabled no)
				(sheetname "")
			)
			(fill
				(thermal_gap 0.5)
				(thermal_bridge_width 0.5)
				(island_removal_mode 0)
			)
			(polygon
				(pts
					(xy 254.344932 -2.8575) (xy 254.344932 -3.8481) (xy 253.836932 -3.8481) (xy 253.836932 -2.8575)
				)
			)
		)
	)
)
